(kicad_pcb
	(version 20260206)
	(generator "pcbnew")
	(generator_version "10.0")
	(general
		(thickness 1.6)
		(legacy_teardrops no)
	)
	(paper "A4")
	(title_block
		(title "v1-tray-backplane — T6M_tray_BP_c_1023_1120.brd")
		(comment 1 "Open CloudServer (Microsoft) / footprints 9-15 of 170")
	)
	(layers
		(0 "F.Cu" signal "TOP")
		(4 "In1.Cu" signal "GND")
		(6 "In2.Cu" signal "IN1")
		(8 "In3.Cu" signal "VCC")
		(10 "In4.Cu" signal "VCC1")
		(12 "In5.Cu" signal "IN2")
		(14 "In6.Cu" signal "GND1")
		(2 "B.Cu" signal "BOTTOM")
		(9 "F.Adhes" user "F.Adhesive")
		(11 "B.Adhes" user "B.Adhesive")
		(13 "F.Paste" user "Package Geometry/Pastemask Top")
		(15 "B.Paste" user "Package Geometry/Pastemask Bottom")
		(5 "F.SilkS" user "Ref Des/Silkscreen Top")
		(7 "B.SilkS" user "Ref Des/Silkscreen Bottom")
		(1 "F.Mask" user "Board Geometry/Soldermask Top")
		(3 "B.Mask" user "Board Geometry/Soldermask Bottom")
		(17 "Dwgs.User" user "User.Drawings")
		(19 "Cmts.User" user "User.Comments")
		(21 "Eco1.User" user "User.Eco1")
		(23 "Eco2.User" user "User.Eco2")
		(25 "Edge.Cuts" user "Board Geometry/Outline")
		(27 "Margin" user)
		(31 "F.CrtYd" user "Package Geometry/Place Bound Top")
		(29 "B.CrtYd" user "Package Geometry/Place Bound Bottom")
		(35 "F.Fab" user "Ref Des/Assembly Top")
		(33 "B.Fab" user "Ref Des/Assembly Bottom")
	)
	(footprint ""
		(layer "F.Cu")
		(at 363.490256 -14.389862 180)
		(property "Reference" "U7"
			(at -5.707888 -10.577576 0)
			(unlocked yes)
			(layer "F.SilkS")
			(effects
				(font
					(size 0.7874 0.5842)
					(thickness 0.1524)
				)
				(justify left)
			)
		)
		(property "Value" ""
			(at 0 0 180)
			(layer "F.Fab")
			(effects
				(font
					(size 1.27 1.27)
				)
			)
		)
		(duplicate_pad_numbers_are_jumpers no)
		(fp_line
			(start 5.500116 3.700018)
			(end 4.191 3.700018)
			(stroke
				(width 0.1524)
				(type default)
			)
			(layer "F.SilkS")
		)
		(fp_line
			(start 5.500116 0.889)
			(end 5.500116 3.700018)
			(stroke
				(width 0.1524)
				(type default)
			)
			(layer "F.SilkS")
		)
		(fp_line
			(start 5.500116 -3.700018)
			(end 5.500116 -0.889)
			(stroke
				(width 0.1524)
				(type default)
			)
			(layer "F.SilkS")
		)
		(fp_line
			(start 3.7846 -3.700018)
			(end 5.500116 -3.700018)
			(stroke
				(width 0.1524)
				(type default)
			)
			(layer "F.SilkS")
		)
		(fp_line
			(start -3.7846 3.700018)
			(end -5.500116 3.700018)
			(stroke
				(width 0.1524)
				(type default)
			)
			(layer "F.SilkS")
		)
		(fp_line
			(start -5.500116 0.635)
			(end -5.500116 3.700018)
			(stroke
				(width 0.1524)
				(type default)
			)
			(layer "F.SilkS")
		)
		(fp_line
			(start -5.500116 -3.700018)
			(end -4.191 -3.700018)
			(stroke
				(width 0.1524)
				(type default)
			)
			(layer "F.SilkS")
		)
		(fp_line
			(start -5.500116 -3.700018)
			(end -5.500116 -0.635)
			(stroke
				(width 0.1524)
				(type default)
			)
			(layer "F.SilkS")
		)
		(fp_poly
			(pts
				(xy -3.387344 5.3848) (xy -3.946144 6.8072) (xy -2.853944 6.8072)
			)
			(stroke
				(width 0)
				(type default)
			)
			(fill yes)
			(layer "F.SilkS")
		)
		(fp_poly
			(pts
				(arc
					(start -4.064 -0.3302)
					(mid -4.8006 -1.0668)
					(end -5.5372 -0.3302)
				)
				(arc
					(start -5.5372 0.3048)
					(mid -5.314015 0.843615)
					(end -4.7752 1.0668)
				)
				(arc
					(start -4.7752 1.0668)
					(mid -4.272306 0.858494)
					(end -4.064 0.3556)
				)
			)
			(stroke
				(width 0)
				(type default)
			)
			(fill no)
			(layer "B.CrtYd")
		)
		(fp_poly
			(pts
				(arc
					(start 3.7338 0)
					(mid 5.8674 0)
					(end 3.7338 0)
				)
			)
			(stroke
				(width 0)
				(type default)
			)
			(fill no)
			(layer "B.CrtYd")
		)
		(fp_rect
			(start -5.5118 5.1308)
			(end 5.5118 -5.1308)
			(stroke
				(width 0)
				(type default)
			)
			(fill no)
			(layer "F.CrtYd")
		)
		(fp_text user "10"
			(at 4.694682 6.283706 0)
			(unlocked yes)
			(layer "F.SilkS")
			(effects
				(font
					(size 0.7874 0.5842)
					(thickness 0.1524)
				)
				(justify left)
			)
		)
		(fp_text user "11"
			(at 3.214624 -6.368288 90)
			(unlocked yes)
			(layer "F.SilkS")
			(effects
				(font
					(size 0.7874 0.5842)
					(thickness 0.1524)
				)
				(justify left)
			)
		)
		(fp_text user "1"
			(at -3.756914 5.902706 0)
			(unlocked yes)
			(layer "F.SilkS")
			(effects
				(font
					(size 0.7874 0.5842)
					(thickness 0.1524)
				)
				(justify left)
			)
		)
		(fp_text user "20"
			(at -4.498848 -8.543036 90)
			(unlocked yes)
			(layer "F.SilkS")
			(effects
				(font
					(size 0.7874 0.5842)
					(thickness 0.1524)
				)
				(justify left)
			)
		)
		(pad "" np_thru_hole oval
			(at -4.800092 0 180)
			(size 0.9652 1.6002)
			(drill oval 0.9652 1.6002)
			(layers "*.Cu" "*.Mask")
			(clearance 0.381)
			(thermal_gap 0.381)
		)
		(pad "" np_thru_hole circle
			(at 4.800092 0 180)
			(size 1.6002 1.6002)
			(drill 1.6002)
			(layers "*.Cu" "*.Mask")
			(clearance 0.381)
			(thermal_gap 0.381)
		)
		(pad "1" smd oval
			(at -3.400044 4.100068 180)
			(size 0.508 2.032)
			(layers "F.Cu" "F.Mask" "F.Paste")
			(net "GND")
		)
		(pad "2" smd oval
			(at -2.599944 4.100068 180)
			(size 0.508 2.032)
			(layers "F.Cu" "F.Mask" "F.Paste")
			(net "ENET10G_3_TX_FAULT")
		)
		(pad "3" smd oval
			(at -1.800098 4.100068 180)
			(size 0.508 2.032)
			(layers "F.Cu" "F.Mask" "F.Paste")
			(net "ENET10G_3_TX_DIS")
		)
		(pad "4" smd oval
			(at -0.999998 4.100068 180)
			(size 0.508 2.032)
			(layers "F.Cu" "F.Mask" "F.Paste")
			(net "ENET10G_3_SDA")
		)
		(pad "5" smd oval
			(at -0.199898 4.100068 180)
			(size 0.508 2.032)
			(layers "F.Cu" "F.Mask" "F.Paste")
			(net "ENET10G_3_SCL")
		)
		(pad "6" smd oval
			(at 0.599948 4.100068 180)
			(size 0.508 2.032)
			(layers "F.Cu" "F.Mask" "F.Paste")
			(net "ENET10G_3_MOD_DEF0")
		)
		(pad "7" smd oval
			(at 1.400048 4.100068 180)
			(size 0.508 2.032)
			(layers "F.Cu" "F.Mask" "F.Paste")
			(net "ENET10G_3_RS0")
		)
		(pad "8" smd oval
			(at 2.199894 4.100068 180)
			(size 0.508 2.032)
			(layers "F.Cu" "F.Mask" "F.Paste")
			(net "ENET10G_3_LOS")
		)
		(pad "9" smd oval
			(at 2.999994 4.100068 180)
			(size 0.508 2.032)
			(layers "F.Cu" "F.Mask" "F.Paste")
			(net "ENET10G_3_RS1")
		)
		(pad "10" smd oval
			(at 3.800094 4.100068 180)
			(size 0.508 2.032)
			(layers "F.Cu" "F.Mask" "F.Paste")
			(net "GND")
		)
		(pad "11" smd oval
			(at 3.400044 -4.100068 180)
			(size 0.508 2.032)
			(layers "F.Cu" "F.Mask" "F.Paste")
			(net "GND")
		)
		(pad "12" smd oval
			(at 2.599944 -4.100068 180)
			(size 0.508 2.032)
			(layers "F.Cu" "F.Mask" "F.Paste")
			(net "ENET10G_3_RDN")
		)
		(pad "13" smd oval
			(at 1.800098 -4.100068 180)
			(size 0.508 2.032)
			(layers "F.Cu" "F.Mask" "F.Paste")
			(net "ENET10G_3_RDP")
		)
		(pad "14" smd oval
			(at 0.999998 -4.100068 180)
			(size 0.508 2.032)
			(layers "F.Cu" "F.Mask" "F.Paste")
			(net "GND")
		)
		(pad "15" smd oval
			(at 0.199898 -4.100068 180)
			(size 0.508 2.032)
			(layers "F.Cu" "F.Mask" "F.Paste")
			(net "P3V3_10G_3_VCCR")
		)
		(pad "16" smd oval
			(at -0.599948 -4.100068 180)
			(size 0.508 2.032)
			(layers "F.Cu" "F.Mask" "F.Paste")
			(net "P3V3_10G_3_VCCT")
		)
		(pad "17" smd oval
			(at -1.400048 -4.100068 180)
			(size 0.508 2.032)
			(layers "F.Cu" "F.Mask" "F.Paste")
			(net "GND")
		)
		(pad "18" smd oval
			(at -2.199894 -4.100068 180)
			(size 0.508 2.032)
			(layers "F.Cu" "F.Mask" "F.Paste")
			(net "ENET10G_3_TDP")
		)
		(pad "19" smd oval
			(at -2.999994 -4.100068 180)
			(size 0.508 2.032)
			(layers "F.Cu" "F.Mask" "F.Paste")
			(net "ENET10G_3_TDN")
		)
		(pad "20" smd oval
			(at -3.800094 -4.100068 180)
			(size 0.508 2.032)
			(layers "F.Cu" "F.Mask" "F.Paste")
			(net "GND")
		)
		(zone
			(layers "F.Cu" "B.Cu" "In1.Cu" "In2.Cu" "In3.Cu" "In4.Cu" "In5.Cu" "In6.Cu")
			(hatch none 0.5)
			(connect_pads
				(clearance 0)
			)
			(min_thickness 0.25)
			(keepout
				(tracks not_allowed)
				(vias allowed)
				(pads allowed)
				(copperpour not_allowed)
				(footprints allowed)
			)
			(placement
				(enabled no)
				(sheetname "")
			)
			(fill
				(thermal_gap 0.5)
				(thermal_bridge_width 0.5)
				(island_removal_mode 0)
			)
			(polygon
				(pts
					(arc
						(start 368.265456 -15.609062)
						(mid 368.912034 -15.34124)
						(end 369.179856 -14.694662)
					)
					(arc
						(start 369.179856 -14.059662)
						(mid 368.290856 -13.170662)
						(end 367.401856 -14.059662)
					)
					(arc
						(start 367.401856 -14.745462)
						(mid 367.654799 -15.356119)
						(end 368.265456 -15.609062)
					)
				)
			)
		)
		(zone
			(layers "F.Cu" "B.Cu" "In1.Cu" "In2.Cu" "In3.Cu" "In4.Cu" "In5.Cu" "In6.Cu")
			(hatch none 0.5)
			(connect_pads
				(clearance 0)
			)
			(min_thickness 0.25)
			(keepout
				(tracks not_allowed)
				(vias allowed)
				(pads allowed)
				(copperpour not_allowed)
				(footprints allowed)
			)
			(placement
				(enabled no)
				(sheetname "")
			)
			(fill
				(thermal_gap 0.5)
				(thermal_bridge_width 0.5)
				(island_removal_mode 0)
			)
			(polygon
				(pts
					(arc
						(start 359.908856 -14.389862)
						(mid 357.470456 -14.389862)
						(end 359.908856 -14.389862)
					)
				)
			)
		)
	)
	(footprint ""
		(layer "F.Cu")
		(at 123.839732 -21.750782 90)
		(property "Reference" "R56"
			(at -6.1214 -59.781948 90)
			(unlocked yes)
			(layer "F.SilkS")
			(effects
				(font
					(size 0.7874 0.5842)
					(thickness 0.1524)
				)
				(justify left)
			)
		)
		(property "Value" ""
			(at 0 0 90)
			(layer "F.Fab")
			(effects
				(font
					(size 1.27 1.27)
				)
			)
		)
		(duplicate_pad_numbers_are_jumpers no)
		(fp_line
			(start 0.7874 -0.4064)
			(end 0.7874 0.4064)
			(stroke
				(width 0.1524)
				(type default)
			)
			(layer "F.SilkS")
		)
		(fp_line
			(start -0.7874 -0.4064)
			(end 0.7874 -0.4064)
			(stroke
				(width 0.1524)
				(type default)
			)
			(layer "F.SilkS")
		)
		(fp_line
			(start 0.7874 0.4064)
			(end -0.7874 0.4064)
			(stroke
				(width 0.1524)
				(type default)
			)
			(layer "F.SilkS")
		)
		(fp_line
			(start -0.7874 0.4064)
			(end -0.7874 -0.4064)
			(stroke
				(width 0.1524)
				(type default)
			)
			(layer "F.SilkS")
		)
		(fp_poly
			(pts
				(xy -0.508 0.2794) (xy -0.508 0.2286) (xy -0.635 0.2286) (xy -0.635 -0.254) (xy -0.5334 -0.254)
				(xy -0.5334 -0.2794) (xy 0.5334 -0.2794) (xy 0.5334 -0.254) (xy 0.635 -0.254) (xy 0.635 0.254) (xy 0.5334 0.254)
				(xy 0.5334 0.2794)
			)
			(stroke
				(width 0)
				(type default)
			)
			(fill no)
			(layer "F.CrtYd")
		)
		(pad "1" smd rect
			(at 0.40005 0 90)
			(size 0.4572 0.508)
			(layers "F.Cu" "F.Mask" "F.Paste")
			(net "GND")
		)
		(pad "2" smd rect
			(at -0.40005 0 90)
			(size 0.4572 0.508)
			(layers "F.Cu" "F.Mask" "F.Paste")
			(net "SKU_PIN_BLAD1_2")
		)
	)
	(footprint ""
		(layer "F.Cu")
		(at 341.771732 -21.790152 90)
		(property "Reference" "R74"
			(at 3.220466 -56.683148 90)
			(unlocked yes)
			(layer "F.SilkS")
			(effects
				(font
					(size 0.7874 0.5842)
					(thickness 0.1524)
				)
				(justify left)
			)
		)
		(property "Value" ""
			(at 0 0 90)
			(layer "F.Fab")
			(effects
				(font
					(size 1.27 1.27)
				)
			)
		)
		(duplicate_pad_numbers_are_jumpers no)
		(fp_line
			(start 0.7874 -0.4064)
			(end 0.7874 0.4064)
			(stroke
				(width 0.1524)
				(type default)
			)
			(layer "F.SilkS")
		)
		(fp_line
			(start -0.7874 -0.4064)
			(end 0.7874 -0.4064)
			(stroke
				(width 0.1524)
				(type default)
			)
			(layer "F.SilkS")
		)
		(fp_line
			(start 0.7874 0.4064)
			(end -0.7874 0.4064)
			(stroke
				(width 0.1524)
				(type default)
			)
			(layer "F.SilkS")
		)
		(fp_line
			(start -0.7874 0.4064)
			(end -0.7874 -0.4064)
			(stroke
				(width 0.1524)
				(type default)
			)
			(layer "F.SilkS")
		)
		(fp_poly
			(pts
				(xy -0.508 0.2794) (xy -0.508 0.2286) (xy -0.635 0.2286) (xy -0.635 -0.254) (xy -0.5334 -0.254)
				(xy -0.5334 -0.2794) (xy 0.5334 -0.2794) (xy 0.5334 -0.254) (xy 0.635 -0.254) (xy 0.635 0.254) (xy 0.5334 0.254)
				(xy 0.5334 0.2794)
			)
			(stroke
				(width 0)
				(type default)
			)
			(fill no)
			(layer "F.CrtYd")
		)
		(pad "1" smd rect
			(at 0.40005 0 90)
			(size 0.4572 0.508)
			(layers "F.Cu" "F.Mask" "F.Paste")
			(net "GND")
		)
		(pad "2" smd rect
			(at -0.40005 0 90)
			(size 0.4572 0.508)
			(layers "F.Cu" "F.Mask" "F.Paste")
			(net "SFP4_PRESENT_N")
		)
	)
	(footprint ""
		(layer "F.Cu")
		(at 313.365134 -39.01567 180)
		(property "Reference" "FS8"
			(at 2.652268 5.545328 0)
			(unlocked yes)
			(layer "F.SilkS")
			(effects
				(font
					(size 0.7874 0.5842)
					(thickness 0.1524)
				)
				(justify left)
			)
		)
		(property "Value" ""
			(at 0 0 180)
			(layer "F.Fab")
			(effects
				(font
					(size 1.27 1.27)
				)
			)
		)
		(duplicate_pad_numbers_are_jumpers no)
		(fp_line
			(start 3.550412 1.050036)
			(end -0.650494 1.050036)
			(stroke
				(width 0.1524)
				(type default)
			)
			(layer "F.SilkS")
		)
		(fp_line
			(start 3.550412 -1.050036)
			(end 3.550412 1.050036)
			(stroke
				(width 0.1524)
				(type default)
			)
			(layer "F.SilkS")
		)
		(fp_line
			(start -0.650494 1.050036)
			(end -0.650494 -1.050036)
			(stroke
				(width 0.1524)
				(type default)
			)
			(layer "F.SilkS")
		)
		(fp_line
			(start -0.650494 -1.050036)
			(end 3.550412 -1.050036)
			(stroke
				(width 0.1524)
				(type default)
			)
			(layer "F.SilkS")
		)
		(fp_poly
			(pts
				(xy 3.228086 -0.9652) (xy 3.228086 -1.100074) (xy -0.327914 -1.100074) (xy -0.327914 -0.9652) (xy -0.556514 -0.9652)
				(xy -0.556514 0.9652) (xy -0.327914 0.9652) (xy -0.327914 1.100074) (xy 3.228086 1.100074) (xy 3.228086 0.9652)
				(xy 3.456686 0.9652) (xy 3.456686 -0.9652)
			)
			(stroke
				(width 0)
				(type default)
			)
			(fill no)
			(layer "F.CrtYd")
		)
		(fp_text user "2"
			(at 5.027422 -0.093472 0)
			(unlocked yes)
			(layer "F.SilkS")
			(effects
				(font
					(size 0.7874 0.5842)
					(thickness 0.1524)
				)
				(justify left)
			)
		)
		(fp_text user "1"
			(at -0.154178 1.989328 0)
			(unlocked yes)
			(layer "F.SilkS")
			(effects
				(font
					(size 0.7874 0.5842)
					(thickness 0.1524)
				)
				(justify left)
			)
		)
		(pad "1" smd rect
			(at 0 0 180)
			(size 1.016 1.8034)
			(layers "F.Cu" "F.Mask" "F.Paste")
			(net "P3V3_BLAD2")
		)
		(pad "2" smd rect
			(at 2.899918 0 180)
			(size 1.016 1.8034)
			(layers "F.Cu" "F.Mask" "F.Paste")
			(net "P3V3_10G_4_VCCR_L")
		)
	)
	(footprint ""
		(layer "F.Cu")
		(at 378.431552 -24.906478)
		(property "Reference" "R51"
			(at 33.528 16.672052 0)
			(unlocked yes)
			(layer "F.SilkS")
			(effects
				(font
					(size 0.7874 0.5842)
					(thickness 0.1524)
				)
				(justify left)
			)
		)
		(property "Value" ""
			(at 0 0 0)
			(layer "F.Fab")
			(effects
				(font
					(size 1.27 1.27)
				)
			)
		)
		(duplicate_pad_numbers_are_jumpers no)
		(fp_line
			(start -0.7874 -0.4064)
			(end 0.7874 -0.4064)
			(stroke
				(width 0.1524)
				(type default)
			)
			(layer "F.SilkS")
		)
		(fp_line
			(start -0.7874 0.4064)
			(end -0.7874 -0.4064)
			(stroke
				(width 0.1524)
				(type default)
			)
			(layer "F.SilkS")
		)
		(fp_line
			(start 0.7874 -0.4064)
			(end 0.7874 0.4064)
			(stroke
				(width 0.1524)
				(type default)
			)
			(layer "F.SilkS")
		)
		(fp_line
			(start 0.7874 0.4064)
			(end -0.7874 0.4064)
			(stroke
				(width 0.1524)
				(type default)
			)
			(layer "F.SilkS")
		)
		(fp_poly
			(pts
				(xy -0.508 0.2794) (xy -0.508 0.2286) (xy -0.635 0.2286) (xy -0.635 -0.254) (xy -0.5334 -0.254)
				(xy -0.5334 -0.2794) (xy 0.5334 -0.2794) (xy 0.5334 -0.254) (xy 0.635 -0.254) (xy 0.635 0.254) (xy 0.5334 0.254)
				(xy 0.5334 0.2794)
			)
			(stroke
				(width 0)
				(type default)
			)
			(fill no)
			(layer "F.CrtYd")
		)
		(pad "1" smd rect
			(at 0.40005 0)
			(size 0.4572 0.508)
			(layers "F.Cu" "F.Mask" "F.Paste")
			(net "GND")
		)
		(pad "2" smd rect
			(at -0.40005 0)
			(size 0.4572 0.508)
			(layers "F.Cu" "F.Mask" "F.Paste")
			(net "ENET10G_3_TX_DIS")
		)
	)
	(footprint ""
		(layer "F.Cu")
		(at 313.315096 -23.367746 -90)
		(property "Reference" "C11"
			(at -1.372108 5.36194 90)
			(unlocked yes)
			(layer "F.SilkS")
			(effects
				(font
					(size 0.7874 0.5842)
					(thickness 0.1524)
				)
				(justify left)
			)
		)
		(property "Value" ""
			(at 0 0 270)
			(layer "F.Fab")
			(effects
				(font
					(size 1.27 1.27)
				)
			)
		)
		(duplicate_pad_numbers_are_jumpers no)
		(fp_line
			(start -0.7874 0.4064)
			(end -0.7874 -0.4064)
			(stroke
				(width 0.1524)
				(type default)
			)
			(layer "F.SilkS")
		)
		(fp_line
			(start 0.7874 0.4064)
			(end -0.7874 0.4064)
			(stroke
				(width 0.1524)
				(type default)
			)
			(layer "F.SilkS")
		)
		(fp_line
			(start 0 0.381)
			(end 0 -0.381)
			(stroke
				(width 0.1524)
				(type default)
			)
			(layer "F.SilkS")
		)
		(fp_line
			(start -0.7874 -0.4064)
			(end 0.7874 -0.4064)
			(stroke
				(width 0.1524)
				(type default)
			)
			(layer "F.SilkS")
		)
		(fp_line
			(start 0.7874 -0.4064)
			(end 0.7874 0.4064)
			(stroke
				(width 0.1524)
				(type default)
			)
			(layer "F.SilkS")
		)
		(fp_poly
			(pts
				(xy -0.5334 0.254) (xy -0.635 0.254) (xy -0.635 0.2286) (xy -0.635 -0.254) (xy -0.5334 -0.254) (xy -0.5334 -0.2794)
				(xy 0.5334 -0.2794) (xy 0.5334 -0.254) (xy 0.635 -0.254) (xy 0.635 0.254) (xy 0.5334 0.254) (xy 0.5334 0.2794)
				(xy -0.508 0.2794) (xy -0.5334 0.2794)
			)
			(stroke
				(width 0)
				(type default)
			)
			(fill no)
			(layer "F.CrtYd")
		)
		(pad "1" smd rect
			(at 0.40005 0 270)
			(size 0.4572 0.508)
			(layers "F.Cu" "F.Mask" "F.Paste")
			(net "P12V")
		)
		(pad "2" smd rect
			(at -0.40005 0 270)
			(size 0.4572 0.508)
			(layers "F.Cu" "F.Mask" "F.Paste")
			(net "GND")
		)
	)
	(footprint ""
		(layer "F.Cu")
		(at 157.781752 -24.165306)
		(property "Reference" "R41"
			(at 33.5534 17.942052 0)
			(unlocked yes)
			(layer "F.SilkS")
			(effects
				(font
					(size 0.7874 0.5842)
					(thickness 0.1524)
				)
				(justify left)
			)
		)
		(property "Value" ""
			(at 0 0 0)
			(layer "F.Fab")
			(effects
				(font
					(size 1.27 1.27)
				)
			)
		)
		(duplicate_pad_numbers_are_jumpers no)
		(fp_line
			(start -0.7874 -0.4064)
			(end 0.7874 -0.4064)
			(stroke
				(width 0.1524)
				(type default)
			)
			(layer "F.SilkS")
		)
		(fp_line
			(start -0.7874 0.4064)
			(end -0.7874 -0.4064)
			(stroke
				(width 0.1524)
				(type default)
			)
			(layer "F.SilkS")
		)
		(fp_line
			(start 0.7874 -0.4064)
			(end 0.7874 0.4064)
			(stroke
				(width 0.1524)
				(type default)
			)
			(layer "F.SilkS")
		)
		(fp_line
			(start 0.7874 0.4064)
			(end -0.7874 0.4064)
			(stroke
				(width 0.1524)
				(type default)
			)
			(layer "F.SilkS")
		)
		(fp_poly
			(pts
				(xy -0.508 0.2794) (xy -0.508 0.2286) (xy -0.635 0.2286) (xy -0.635 -0.254) (xy -0.5334 -0.254)
				(xy -0.5334 -0.2794) (xy 0.5334 -0.2794) (xy 0.5334 -0.254) (xy 0.635 -0.254) (xy 0.635 0.254) (xy 0.5334 0.254)
				(xy 0.5334 0.2794)
			)
			(stroke
				(width 0)
				(type default)
			)
			(fill no)
			(layer "F.CrtYd")
		)
		(pad "1" smd rect
			(at 0.40005 0)
			(size 0.4572 0.508)
			(layers "F.Cu" "F.Mask" "F.Paste")
			(net "GND")
		)
		(pad "2" smd rect
			(at -0.40005 0)
			(size 0.4572 0.508)
			(layers "F.Cu" "F.Mask" "F.Paste")
			(net "ENET10G_1_TX_DIS")
		)
	)
)
